# S9S_MB_2U (Grand Teton) — schematic netlist excerpt (pin names and nets, part order shuffled) for the footprints in the layout excerpt that follows; sources: Cadence DE-HDL packaged netlist, KiCad conversion of 03242023_DA0F0TMBIJ0_F0T_Motherboard_J_brd_V01_OCP.brd

C346  Q_CAP  47UF 4V 20% X6S  pkg C0805  page 79 : A = PVCCIN_CPU1 ; B = GND
R741  Q_RES  150 1% CHIP  pkg 0402LF  page 133 : A = PVNN_TERM_CPU0 ; B = JTAG_MUX_CPU0_GTL_TDI
C1941  Q_CAP  0.1UF 25V 10% X7R  pkg 0402  page 217 : A = P3V3_AUX_FPGA_VCCIO3 ; B = GND

(kicad_pcb
	(version 20260206)
	(generator "pcbnew")
	(generator_version "10.0")
	(general
		(thickness 1.6)
		(legacy_teardrops no)
	)
	(paper "A4")
	(title_block
		(title "03242023_DA0F0TMBIJ0_F0T_Motherboard_J_brd_V01_OCP.brd")
		(comment 1 "Grand Teton / footprints 4719-4721 of 6105")
	)
	(layers
		(0 "F.Cu" signal "TOP")
		(4 "In1.Cu" signal "GND")
		(6 "In2.Cu" signal "IN1")
		(8 "In3.Cu" signal "GND1")
		(10 "In4.Cu" signal "IN2")
		(12 "In5.Cu" signal "GND2")
		(14 "In6.Cu" signal "IN3")
		(16 "In7.Cu" signal "GND3")
		(18 "In8.Cu" signal "VCC")
		(20 "In9.Cu" signal "VCC1")
		(22 "In10.Cu" signal "GND4")
		(24 "In11.Cu" signal "IN4")
		(26 "In12.Cu" signal "GND5")
		(28 "In13.Cu" signal "IN5")
		(30 "In14.Cu" signal "GND6")
		(32 "In15.Cu" signal "IN6")
		(34 "In16.Cu" signal "GND7")
		(2 "B.Cu" signal "BOTTOM")
		(9 "F.Adhes" user "F.Adhesive")
		(11 "B.Adhes" user "B.Adhesive")
		(13 "F.Paste" user "Package Geometry/Pastemask Top")
		(15 "B.Paste" user "Package Geometry/Pastemask Bottom")
		(5 "F.SilkS" user "Ref Des/Silkscreen Top")
		(7 "B.SilkS" user "Ref Des/Silkscreen Bottom")
		(1 "F.Mask" user "Board Geometry/Soldermask Top")
		(3 "B.Mask" user "Board Geometry/Soldermask Bottom")
		(17 "Dwgs.User" user "User.Drawings")
		(19 "Cmts.User" user "User.Comments")
		(21 "Eco1.User" user "User.Eco1")
		(23 "Eco2.User" user "User.Eco2")
		(25 "Edge.Cuts" user "Board Geometry/Outline")
		(27 "Margin" user)
		(31 "F.CrtYd" user "Package Geometry/Place Bound Top")
		(29 "B.CrtYd" user "Package Geometry/Place Bound Bottom")
		(35 "F.Fab" user "Ref Des/Assembly Top")
		(33 "B.Fab" user "Ref Des/Assembly Bottom")
	)
	(footprint ""
		(layer "B.Cu")
		(at 337.903312 -187.996068 90)
		(property "Reference" "R741"
			(at 0 0 90)
			(layer "B.SilkS")
			(hide yes)
			(effects
				(font
					(size 1.27 1.27)
				)
				(justify mirror)
			)
		)
		(property "Value" ""
			(at 0 0 90)
			(layer "B.Fab")
			(effects
				(font
					(size 1.27 1.27)
				)
				(justify mirror)
			)
		)
		(duplicate_pad_numbers_are_jumpers no)
		(fp_line
			(start 0.7874 -0.4064)
			(end -0.7874 -0.4064)
			(stroke
				(width 0.1524)
				(type default)
			)
			(layer "B.SilkS")
		)
		(fp_line
			(start -0.7874 -0.4064)
			(end -0.7874 0.4064)
			(stroke
				(width 0.1524)
				(type default)
			)
			(layer "B.SilkS")
		)
		(fp_line
			(start 0.7874 0.4064)
			(end 0.7874 -0.4064)
			(stroke
				(width 0.1524)
				(type default)
			)
			(layer "B.SilkS")
		)
		(fp_line
			(start -0.7874 0.4064)
			(end 0.7874 0.4064)
			(stroke
				(width 0.1524)
				(type default)
			)
			(layer "B.SilkS")
		)
		(fp_line
			(start 0.67945 -0.305054)
			(end 0.12065 -0.305054)
			(stroke
				(width 0.1)
				(type default)
			)
			(layer "B.Fab")
		)
		(fp_line
			(start 0.12065 -0.305054)
			(end 0.12065 -0.2794)
			(stroke
				(width 0.1)
				(type default)
			)
			(layer "B.Fab")
		)
		(fp_line
			(start -0.12065 -0.3048)
			(end -0.67945 -0.3048)
			(stroke
				(width 0.1)
				(type default)
			)
			(layer "B.Fab")
		)
		(fp_line
			(start -0.67945 -0.3048)
			(end -0.67945 0.3048)
			(stroke
				(width 0.1)
				(type default)
			)
			(layer "B.Fab")
		)
		(fp_line
			(start 0.12065 -0.2794)
			(end -0.12065 -0.2794)
			(stroke
				(width 0.1)
				(type default)
			)
			(layer "B.Fab")
		)
		(fp_line
			(start -0.12065 -0.2794)
			(end -0.12065 -0.3048)
			(stroke
				(width 0.1)
				(type default)
			)
			(layer "B.Fab")
		)
		(fp_line
			(start 0.12065 0.2794)
			(end 0.12065 0.3048)
			(stroke
				(width 0.1)
				(type default)
			)
			(layer "B.Fab")
		)
		(fp_line
			(start -0.120396 0.2794)
			(end 0.12065 0.2794)
			(stroke
				(width 0.1)
				(type default)
			)
			(layer "B.Fab")
		)
		(fp_line
			(start 0.67945 0.3048)
			(end 0.67945 -0.305054)
			(stroke
				(width 0.1)
				(type default)
			)
			(layer "B.Fab")
		)
		(fp_line
			(start 0.12065 0.3048)
			(end 0.67945 0.3048)
			(stroke
				(width 0.1)
				(type default)
			)
			(layer "B.Fab")
		)
		(fp_line
			(start -0.120396 0.3048)
			(end -0.120396 0.2794)
			(stroke
				(width 0.1)
				(type default)
			)
			(layer "B.Fab")
		)
		(fp_line
			(start -0.67945 0.3048)
			(end -0.120396 0.3048)
			(stroke
				(width 0.1)
				(type default)
			)
			(layer "B.Fab")
		)
		(pad "1" smd circle
			(at 0.40005 0 270)
			(size 0 0)
			(layers "B.Cu" "B.Mask" "B.Paste")
			(net "PVNN_TERM_CPU0")
		)
		(pad "2" smd circle
			(at -0.40005 0 270)
			(size 0 0)
			(layers "B.Cu" "B.Mask" "B.Paste")
			(net "JTAG_MUX_CPU0_GTL_TDI")
		)
	)
	(footprint ""
		(layer "B.Cu")
		(at 182.68188 -102.707948)
		(property "Reference" "C1941"
			(at 0 0 0)
			(layer "B.SilkS")
			(hide yes)
			(effects
				(font
					(size 1.27 1.27)
				)
				(justify mirror)
			)
		)
		(property "Value" ""
			(at 0 0 0)
			(layer "B.Fab")
			(effects
				(font
					(size 1.27 1.27)
				)
				(justify mirror)
			)
		)
		(duplicate_pad_numbers_are_jumpers no)
		(fp_line
			(start -0.7874 -0.4064)
			(end -0.7874 0.4064)
			(stroke
				(width 0.1524)
				(type default)
			)
			(layer "B.SilkS")
		)
		(fp_line
			(start -0.7874 0.4064)
			(end 0.7874 0.4064)
			(stroke
				(width 0.1524)
				(type default)
			)
			(layer "B.SilkS")
		)
		(fp_line
			(start 0.7874 -0.4064)
			(end -0.7874 -0.4064)
			(stroke
				(width 0.1524)
				(type default)
			)
			(layer "B.SilkS")
		)
		(fp_line
			(start 0.7874 0.4064)
			(end 0.7874 -0.4064)
			(stroke
				(width 0.1524)
				(type default)
			)
			(layer "B.SilkS")
		)
		(fp_line
			(start -0.67945 -0.3048)
			(end -0.67945 0.3048)
			(stroke
				(width 0.1)
				(type default)
			)
			(layer "B.Fab")
		)
		(fp_line
			(start -0.67945 0.3048)
			(end -0.120396 0.3048)
			(stroke
				(width 0.1)
				(type default)
			)
			(layer "B.Fab")
		)
		(fp_line
			(start -0.12065 -0.3048)
			(end -0.67945 -0.3048)
			(stroke
				(width 0.1)
				(type default)
			)
			(layer "B.Fab")
		)
		(fp_line
			(start -0.12065 -0.2794)
			(end -0.12065 -0.3048)
			(stroke
				(width 0.1)
				(type default)
			)
			(layer "B.Fab")
		)
		(fp_line
			(start -0.120396 0.2794)
			(end 0.12065 0.2794)
			(stroke
				(width 0.1)
				(type default)
			)
			(layer "B.Fab")
		)
		(fp_line
			(start -0.120396 0.3048)
			(end -0.120396 0.2794)
			(stroke
				(width 0.1)
				(type default)
			)
			(layer "B.Fab")
		)
		(fp_line
			(start 0.12065 -0.305054)
			(end 0.12065 -0.2794)
			(stroke
				(width 0.1)
				(type default)
			)
			(layer "B.Fab")
		)
		(fp_line
			(start 0.12065 -0.2794)
			(end -0.12065 -0.2794)
			(stroke
				(width 0.1)
				(type default)
			)
			(layer "B.Fab")
		)
		(fp_line
			(start 0.12065 0.2794)
			(end 0.12065 0.3048)
			(stroke
				(width 0.1)
				(type default)
			)
			(layer "B.Fab")
		)
		(fp_line
			(start 0.12065 0.3048)
			(end 0.67945 0.3048)
			(stroke
				(width 0.1)
				(type default)
			)
			(layer "B.Fab")
		)
		(fp_line
			(start 0.67945 -0.305054)
			(end 0.12065 -0.305054)
			(stroke
				(width 0.1)
				(type default)
			)
			(layer "B.Fab")
		)
		(fp_line
			(start 0.67945 0.3048)
			(end 0.67945 -0.305054)
			(stroke
				(width 0.1)
				(type default)
			)
			(layer "B.Fab")
		)
		(pad "1" smd circle
			(at 0.40005 0 180)
			(size 0 0)
			(layers "B.Cu" "B.Mask" "B.Paste")
			(net "P3V3_AUX_FPGA_VCCIO3")
		)
		(pad "2" smd circle
			(at -0.40005 0 180)
			(size 0 0)
			(layers "B.Cu" "B.Mask" "B.Paste")
			(net "GND")
		)
	)
	(footprint ""
		(layer "B.Cu")
		(at 108.845604 -296.05478 180)
		(property "Reference" "C346"
			(at 0 0 0)
			(layer "B.SilkS")
			(hide yes)
			(effects
				(font
					(size 1.27 1.27)
				)
				(justify mirror)
			)
		)
		(property "Value" ""
			(at 0 0 0)
			(layer "B.Fab")
			(effects
				(font
					(size 1.27 1.27)
				)
				(justify mirror)
			)
		)
		(duplicate_pad_numbers_are_jumpers no)
		(fp_line
			(start 1.524 0.762)
			(end 1.524 -0.762)
			(stroke
				(width 0.1524)
				(type default)
			)
			(layer "B.SilkS")
		)
		(fp_line
			(start 1.524 -0.762)
			(end -1.524 -0.762)
			(stroke
				(width 0.1524)
				(type default)
			)
			(layer "B.SilkS")
		)
		(fp_line
			(start -1.524 0.762)
			(end 1.524 0.762)
			(stroke
				(width 0.1524)
				(type default)
			)
			(layer "B.SilkS")
		)
		(fp_line
			(start -1.524 -0.762)
			(end -1.524 0.762)
			(stroke
				(width 0.1524)
				(type default)
			)
			(layer "B.SilkS")
		)
		(fp_line
			(start 1.1049 0.724916)
			(end -1.1049 0.724916)
			(stroke
				(width 0.1)
				(type default)
			)
			(layer "B.Fab")
		)
		(fp_line
			(start 1.1049 -0.724916)
			(end 1.1049 0.724916)
			(stroke
				(width 0.1)
				(type default)
			)
			(layer "B.Fab")
		)
		(fp_line
			(start -1.1049 0.724916)
			(end -1.1049 -0.724916)
			(stroke
				(width 0.1)
				(type default)
			)
			(layer "B.Fab")
		)
		(fp_line
			(start -1.1049 -0.724916)
			(end 1.1049 -0.724916)
			(stroke
				(width 0.1)
				(type default)
			)
			(layer "B.Fab")
		)
		(pad "1" smd rect
			(at 0.889 0 180)
			(size 1.016 1.27)
			(layers "B.Cu" "B.Mask" "B.Paste")
			(net "PVCCIN_CPU1")
		)
		(pad "2" smd rect
			(at -0.889 0 180)
			(size 1.016 1.27)
			(layers "B.Cu" "B.Mask" "B.Paste")
			(net "GND")
		)
	)
)
